FILE_TYPE=LIBRARY_PARTS;
primitive 'SCD1U16V2KX-3GP_SMD-BCG';
  pin
    '1':
      PIN_NUMBER='(1)';
      PIN_TYPE='ANALOG';
      NO_LOAD_CHECK='Both';
      NO_IO_CHECK='Both';
      NO_ASSERT_CHECK='TRUE';
      NO_DIR_CHECK='TRUE';
      ALLOW_CONNECT='TRUE';
    '2':
      PIN_NUMBER='(2)';
      PIN_TYPE='ANALOG';
      NO_LOAD_CHECK='Both';
      NO_IO_CHECK='Both';
      NO_ASSERT_CHECK='TRUE';
      NO_DIR_CHECK='TRUE';
      ALLOW_CONNECT='TRUE';
  end_pin;
  body
    PART_NAME='SCD1U16V2KX-3GP';
    BODY_NAME='SCD1U16V2KX-3GP';
    PHYS_DES_PREFIX='C';
    CLASS='DISCRETE';
  end_body;
end_primitive;

END.
